# S9S_MB_2U (Grand Teton) — schematic netlist excerpt (pin names and nets, part order shuffled) for the footprints in the layout excerpt that follows; sources: Cadence DE-HDL packaged netlist, KiCad conversion of 03242023_DA0F0TMBIJ0_F0T_Motherboard_J_brd_V01_OCP.brd

J63  PICOPROBE_BXA  DELTA-L 4.0 EMPTY  pkg TRIANG_LAUNCH_3PXB  page 308
  \1_p\  = DELTA_L_85_5INCH_TOP_DP
  \2_n\  = DELTA_L_85_5INCH_TOP_DN
  \3_g\  = DELTA_L_GND_1

(kicad_pcb
	(version 20260206)
	(generator "pcbnew")
	(generator_version "10.0")
	(general
		(thickness 1.6)
		(legacy_teardrops no)
	)
	(paper "A4")
	(title_block
		(title "03242023_DA0F0TMBIJ0_F0T_Motherboard_J_brd_V01_OCP.brd")
		(comment 1 "Grand Teton / footprints 3654-3654 of 6105")
	)
	(layers
		(0 "F.Cu" signal "TOP")
		(4 "In1.Cu" signal "GND")
		(6 "In2.Cu" signal "IN1")
		(8 "In3.Cu" signal "GND1")
		(10 "In4.Cu" signal "IN2")
		(12 "In5.Cu" signal "GND2")
		(14 "In6.Cu" signal "IN3")
		(16 "In7.Cu" signal "GND3")
		(18 "In8.Cu" signal "VCC")
		(20 "In9.Cu" signal "VCC1")
		(22 "In10.Cu" signal "GND4")
		(24 "In11.Cu" signal "IN4")
		(26 "In12.Cu" signal "GND5")
		(28 "In13.Cu" signal "IN5")
		(30 "In14.Cu" signal "GND6")
		(32 "In15.Cu" signal "IN6")
		(34 "In16.Cu" signal "GND7")
		(2 "B.Cu" signal "BOTTOM")
		(9 "F.Adhes" user "F.Adhesive")
		(11 "B.Adhes" user "B.Adhesive")
		(13 "F.Paste" user "Package Geometry/Pastemask Top")
		(15 "B.Paste" user "Package Geometry/Pastemask Bottom")
		(5 "F.SilkS" user "Ref Des/Silkscreen Top")
		(7 "B.SilkS" user "Ref Des/Silkscreen Bottom")
		(1 "F.Mask" user "Board Geometry/Soldermask Top")
		(3 "B.Mask" user "Board Geometry/Soldermask Bottom")
		(17 "Dwgs.User" user "User.Drawings")
		(19 "Cmts.User" user "User.Comments")
		(21 "Eco1.User" user "User.Eco1")
		(23 "Eco2.User" user "User.Eco2")
		(25 "Edge.Cuts" user "Board Geometry/Outline")
		(27 "Margin" user)
		(31 "F.CrtYd" user "Package Geometry/Place Bound Top")
		(29 "B.CrtYd" user "Package Geometry/Place Bound Bottom")
		(35 "F.Fab" user "Ref Des/Assembly Top")
		(33 "B.Fab" user "Ref Des/Assembly Bottom")
	)
	(footprint ""
		(layer "F.Cu")
		(at 378.099574 -4.696206 180)
		(property "Reference" "J63"
			(at -4.451096 -1.140206 90)
			(unlocked yes)
			(layer "F.SilkS")
			(effects
				(font
					(size 0.7874 0.5842)
					(thickness 0.1524)
				)
				(justify left)
			)
		)
		(property "Value" ""
			(at 0 0 180)
			(layer "F.Fab")
			(effects
				(font
					(size 1.27 1.27)
				)
			)
		)
		(duplicate_pad_numbers_are_jumpers no)
		(fp_line
			(start 1.2192 2.1082)
			(end -1.2192 2.1082)
			(stroke
				(width 0.1524)
				(type default)
			)
			(layer "F.SilkS")
		)
		(fp_line
			(start 1.2192 -2.1082)
			(end 1.2192 2.1082)
			(stroke
				(width 0.1524)
				(type default)
			)
			(layer "F.SilkS")
		)
		(fp_line
			(start -1.2192 2.1082)
			(end -1.2192 -2.1082)
			(stroke
				(width 0.1524)
				(type default)
			)
			(layer "F.SilkS")
		)
		(fp_line
			(start -1.2192 -2.1082)
			(end 1.2192 -2.1082)
			(stroke
				(width 0.1524)
				(type default)
			)
			(layer "F.SilkS")
		)
		(pad "" np_thru_hole circle
			(at -2.8829 -1.27 90)
			(size 1.0414 1.0414)
			(drill 1.0414)
			(layers "*.Cu" "*.Mask")
			(clearance 0.381)
			(thermal_gap 0.381)
		)
		(pad "" np_thru_hole circle
			(at -2.8829 1.27 90)
			(size 1.0414 1.0414)
			(drill 1.0414)
			(layers "*.Cu" "*.Mask")
			(clearance 0.381)
			(thermal_gap 0.381)
		)
		(pad "" np_thru_hole circle
			(at 3.4671 -1.27 90)
			(size 1.0414 1.0414)
			(drill 1.0414)
			(layers "*.Cu" "*.Mask")
			(clearance 0.381)
			(thermal_gap 0.381)
		)
		(pad "" np_thru_hole circle
			(at 3.4671 1.27 90)
			(size 1.0414 1.0414)
			(drill 1.0414)
			(layers "*.Cu" "*.Mask")
			(clearance 0.381)
			(thermal_gap 0.381)
		)
		(pad "1" smd rect
			(at 0.8255 -0.249936 90)
			(size 0.3048 0.508)
			(layers "F.Cu" "F.Mask" "F.Paste")
			(net "DELTA_L_85_5INCH_TOP_DP")
		)
		(pad "2" smd rect
			(at 0.8255 0.249936 90)
			(size 0.3048 0.508)
			(layers "F.Cu" "F.Mask" "F.Paste")
			(net "DELTA_L_85_5INCH_TOP_DN")
		)
		(pad "3" smd circle
			(at 0 0 180)
			(size 0 0)
			(layers "F.Cu" "F.Mask" "F.Paste")
			(net "DELTA_L_GND_1")
		)
		(zone
			(layer "F.Cu")
			(hatch none 0.5)
			(connect_pads
				(clearance 0)
			)
			(min_thickness 0.25)
			(keepout
				(tracks not_allowed)
				(vias allowed)
				(pads allowed)
				(copperpour not_allowed)
				(footprints allowed)
			)
			(placement
				(enabled no)
				(sheetname "")
			)
			(fill
				(thermal_gap 0.5)
				(thermal_bridge_width 0.5)
				(island_removal_mode 0)
			)
			(polygon
				(pts
					(xy 376.981974 -4.147566) (xy 376.981974 -4.24307) (xy 377.578874 -4.24307) (xy 377.578874 -4.64947)
					(xy 376.981974 -4.64947) (xy 376.981974 -4.742942) (xy 377.578874 -4.742942) (xy 377.578874 -5.149342)
					(xy 376.981974 -5.149342) (xy 376.981974 -5.244846) (xy 377.680474 -5.244846) (xy 377.680474 -4.147566)
				)
			)
		)
		(zone
			(layers "F.Cu" "B.Cu" "In1.Cu" "In2.Cu" "In3.Cu" "In4.Cu" "In5.Cu" "In6.Cu"
				"In7.Cu" "In8.Cu" "In9.Cu" "In10.Cu" "In11.Cu" "In12.Cu" "In13.Cu" "In14.Cu"
				"In15.Cu" "In16.Cu"
			)
			(hatch none 0.5)
			(connect_pads
				(clearance 0)
			)
			(min_thickness 0.25)
			(keepout
				(tracks not_allowed)
				(vias allowed)
				(pads allowed)
				(copperpour not_allowed)
				(footprints allowed)
			)
			(placement
				(enabled no)
				(sheetname "")
			)
			(fill
				(thermal_gap 0.5)
				(thermal_bridge_width 0.5)
				(island_removal_mode 0)
			)
			(polygon
				(pts
					(arc
						(start 375.559574 -5.966206)
						(mid 373.705374 -5.966206)
						(end 375.559574 -5.966206)
					)
				)
			)
		)
		(zone
			(layers "F.Cu" "B.Cu" "In1.Cu" "In2.Cu" "In3.Cu" "In4.Cu" "In5.Cu" "In6.Cu"
				"In7.Cu" "In8.Cu" "In9.Cu" "In10.Cu" "In11.Cu" "In12.Cu" "In13.Cu" "In14.Cu"
				"In15.Cu" "In16.Cu"
			)
			(hatch none 0.5)
			(connect_pads
				(clearance 0)
			)
			(min_thickness 0.25)
			(keepout
				(tracks not_allowed)
				(vias allowed)
				(pads allowed)
				(copperpour not_allowed)
				(footprints allowed)
			)
			(placement
				(enabled no)
				(sheetname "")
			)
			(fill
				(thermal_gap 0.5)
				(thermal_bridge_width 0.5)
				(island_removal_mode 0)
			)
			(polygon
				(pts
					(arc
						(start 375.559574 -3.426206)
						(mid 373.705374 -3.426206)
						(end 375.559574 -3.426206)
					)
				)
			)
		)
		(zone
			(layers "F.Cu" "B.Cu" "In1.Cu" "In2.Cu" "In3.Cu" "In4.Cu" "In5.Cu" "In6.Cu"
				"In7.Cu" "In8.Cu" "In9.Cu" "In10.Cu" "In11.Cu" "In12.Cu" "In13.Cu" "In14.Cu"
				"In15.Cu" "In16.Cu"
			)
			(hatch none 0.5)
			(connect_pads
				(clearance 0)
			)
			(min_thickness 0.25)
			(keepout
				(tracks not_allowed)
				(vias allowed)
				(pads allowed)
				(copperpour not_allowed)
				(footprints allowed)
			)
			(placement
				(enabled no)
				(sheetname "")
			)
			(fill
				(thermal_gap 0.5)
				(thermal_bridge_width 0.5)
				(island_removal_mode 0)
			)
			(polygon
				(pts
					(arc
						(start 381.909574 -5.966206)
						(mid 380.055374 -5.966206)
						(end 381.909574 -5.966206)
					)
				)
			)
		)
		(zone
			(layers "F.Cu" "B.Cu" "In1.Cu" "In2.Cu" "In3.Cu" "In4.Cu" "In5.Cu" "In6.Cu"
				"In7.Cu" "In8.Cu" "In9.Cu" "In10.Cu" "In11.Cu" "In12.Cu" "In13.Cu" "In14.Cu"
				"In15.Cu" "In16.Cu"
			)
			(hatch none 0.5)
			(connect_pads
				(clearance 0)
			)
			(min_thickness 0.25)
			(keepout
				(tracks not_allowed)
				(vias allowed)
				(pads allowed)
				(copperpour not_allowed)
				(footprints allowed)
			)
			(placement
				(enabled no)
				(sheetname "")
			)
			(fill
				(thermal_gap 0.5)
				(thermal_bridge_width 0.5)
				(island_removal_mode 0)
			)
			(polygon
				(pts
					(arc
						(start 381.909574 -3.426206)
						(mid 380.055374 -3.426206)
						(end 381.909574 -3.426206)
					)
				)
			)
		)
	)
)
